(kicad_pcb
	(version 20260206)
	(generator "pcbnew")
	(generator_version "10.0")
	(general
		(thickness 1.6)
		(legacy_teardrops no)
	)
	(paper "A4")
	(title_block
		(title "Wiwynn_Tioga_Pass_MB.brd")
		(comment 1 "Tioga Pass / footprints 1591-1597 of 4770")
	)
	(layers
		(0 "F.Cu" signal "TOP")
		(4 "In1.Cu" signal "L2GND")
		(6 "In2.Cu" signal "L3")
		(8 "In3.Cu" signal "L4GND")
		(10 "In4.Cu" signal "L5")
		(12 "In5.Cu" signal "L6GND")
		(14 "In6.Cu" signal "L7VCC")
		(16 "In7.Cu" signal "L8VCC")
		(18 "In8.Cu" signal "L9GND")
		(20 "In9.Cu" signal "L10")
		(22 "In10.Cu" signal "L11GND")
		(24 "In11.Cu" signal "L12")
		(26 "In12.Cu" signal "L13GND")
		(2 "B.Cu" signal "BOTTOM")
		(9 "F.Adhes" user "F.Adhesive")
		(11 "B.Adhes" user "B.Adhesive")
		(13 "F.Paste" user "Package Geometry/Pastemask Top")
		(15 "B.Paste" user "Package Geometry/Pastemask Bottom")
		(5 "F.SilkS" user "Ref Des/Silkscreen Top")
		(7 "B.SilkS" user "Ref Des/Silkscreen Bottom")
		(1 "F.Mask" user "Board Geometry/Soldermask Top")
		(3 "B.Mask" user "Board Geometry/Soldermask Bottom")
		(17 "Dwgs.User" user "User.Drawings")
		(19 "Cmts.User" user "User.Comments")
		(21 "Eco1.User" user "User.Eco1")
		(23 "Eco2.User" user "User.Eco2")
		(25 "Edge.Cuts" user "Board Geometry/Outline")
		(27 "Margin" user)
		(31 "F.CrtYd" user "Package Geometry/Place Bound Top")
		(29 "B.CrtYd" user "Package Geometry/Place Bound Bottom")
		(35 "F.Fab" user "Ref Des/Assembly Top")
		(33 "B.Fab" user "Ref Des/Assembly Bottom")
	)
	(footprint ""
		(layer "F.Cu")
		(at 370.967 -97.155 180)
		(property "Reference" "R7W1"
			(at -0.8382 -0.67818 180)
			(unlocked yes)
			(layer "F.SilkS")
			(effects
				(font
					(size 0.4064 0.254)
					(thickness 0.1524)
				)
				(justify left)
			)
		)
		(property "Value" ""
			(at 0 0 180)
			(layer "F.Fab")
			(effects
				(font
					(size 1.27 1.27)
				)
			)
		)
		(duplicate_pad_numbers_are_jumpers no)
		(fp_poly
			(pts
				(xy -0.2794 -0.1016) (xy 0.2794 -0.1016) (xy 0.2794 0.9906) (xy -0.2794 0.9906)
			)
			(stroke
				(width 0)
				(type default)
			)
			(fill no)
			(layer "F.CrtYd")
		)
		(fp_line
			(start 0.2794 0.9906)
			(end 0.2794 -0.1016)
			(stroke
				(width 0.1)
				(type default)
			)
			(layer "F.Fab")
		)
		(fp_line
			(start 0.2794 -0.1016)
			(end -0.2794 -0.1016)
			(stroke
				(width 0.1)
				(type default)
			)
			(layer "F.Fab")
		)
		(fp_line
			(start -0.2794 0.9906)
			(end 0.2794 0.9906)
			(stroke
				(width 0.1)
				(type default)
			)
			(layer "F.Fab")
		)
		(fp_line
			(start -0.2794 -0.1016)
			(end -0.2794 0.9906)
			(stroke
				(width 0.1)
				(type default)
			)
			(layer "F.Fab")
		)
		(pad "1" smd rect
			(at 0 0 180)
			(size 0.508 0.508)
			(layers "F.Cu" "F.Mask" "F.Paste")
			(net "FM_SLPS3_N")
		)
		(pad "2" smd rect
			(at 0 0.889 180)
			(size 0.508 0.508)
			(layers "F.Cu" "F.Mask" "F.Paste")
			(net "FM_SLPS3_R_N")
		)
		(zone
			(layer "F.Cu")
			(hatch none 0.5)
			(connect_pads
				(clearance 0)
			)
			(min_thickness 0.25)
			(keepout
				(tracks not_allowed)
				(vias allowed)
				(pads allowed)
				(copperpour not_allowed)
				(footprints allowed)
			)
			(placement
				(enabled no)
				(sheetname "")
			)
			(fill
				(thermal_gap 0.5)
				(thermal_bridge_width 0.5)
				(island_removal_mode 0)
			)
			(polygon
				(pts
					(xy 371.221 -97.79) (xy 370.713 -97.79) (xy 370.713 -97.409) (xy 371.221 -97.409)
				)
			)
		)
		(zone
			(layer "F.Cu")
			(hatch none 0.5)
			(connect_pads
				(clearance 0)
			)
			(min_thickness 0.25)
			(keepout
				(tracks allowed)
				(vias not_allowed)
				(pads allowed)
				(copperpour not_allowed)
				(footprints allowed)
			)
			(placement
				(enabled no)
				(sheetname "")
			)
			(fill
				(thermal_gap 0.5)
				(thermal_bridge_width 0.5)
				(island_removal_mode 0)
			)
			(polygon
				(pts
					(xy 371.221 -97.409) (xy 370.713 -97.409) (xy 370.713 -97.79) (xy 371.221 -97.79)
				)
			)
		)
	)
	(footprint ""
		(layer "F.Cu")
		(at 407.67 -20.2565)
		(property "Reference" "C1U21"
			(at 0 0 0)
			(layer "F.SilkS")
			(hide yes)
			(effects
				(font
					(size 1.27 1.27)
				)
			)
		)
		(property "Value" ""
			(at 0 0 0)
			(layer "F.Fab")
			(effects
				(font
					(size 1.27 1.27)
				)
			)
		)
		(duplicate_pad_numbers_are_jumpers no)
		(fp_poly
			(pts
				(xy 0.3048 -0.1016) (xy 0.3048 0.9906) (xy -0.3048 0.9906) (xy -0.3048 -0.1016)
			)
			(stroke
				(width 0)
				(type default)
			)
			(fill no)
			(layer "F.CrtYd")
		)
		(fp_line
			(start -0.3048 -0.1016)
			(end -0.3048 0.9906)
			(stroke
				(width 0.1)
				(type default)
			)
			(layer "F.Fab")
		)
		(fp_line
			(start -0.3048 0.9906)
			(end 0.3048 0.9906)
			(stroke
				(width 0.1)
				(type default)
			)
			(layer "F.Fab")
		)
		(fp_line
			(start 0.3048 -0.1016)
			(end -0.3048 -0.1016)
			(stroke
				(width 0.1)
				(type default)
			)
			(layer "F.Fab")
		)
		(fp_line
			(start 0.3048 0.9906)
			(end 0.3048 -0.1016)
			(stroke
				(width 0.1)
				(type default)
			)
			(layer "F.Fab")
		)
		(pad "1" smd rect
			(at 0 0)
			(size 0.508 0.508)
			(layers "F.Cu" "F.Mask" "F.Paste")
			(net "A_P1V05_STBY_PCH_SENSOR")
		)
		(pad "2" smd rect
			(at 0 0.889)
			(size 0.508 0.508)
			(layers "F.Cu" "F.Mask" "F.Paste")
			(net "GND")
		)
		(zone
			(layer "F.Cu")
			(hatch none 0.5)
			(connect_pads
				(clearance 0)
			)
			(min_thickness 0.25)
			(keepout
				(tracks allowed)
				(vias not_allowed)
				(pads allowed)
				(copperpour not_allowed)
				(footprints allowed)
			)
			(placement
				(enabled no)
				(sheetname "")
			)
			(fill
				(thermal_gap 0.5)
				(thermal_bridge_width 0.5)
				(island_removal_mode 0)
			)
			(polygon
				(pts
					(xy 407.416 -20.0025) (xy 407.924 -20.0025) (xy 407.924 -19.6215) (xy 407.416 -19.6215)
				)
			)
		)
		(zone
			(layer "F.Cu")
			(hatch none 0.5)
			(connect_pads
				(clearance 0)
			)
			(min_thickness 0.25)
			(keepout
				(tracks not_allowed)
				(vias allowed)
				(pads allowed)
				(copperpour not_allowed)
				(footprints allowed)
			)
			(placement
				(enabled no)
				(sheetname "")
			)
			(fill
				(thermal_gap 0.5)
				(thermal_bridge_width 0.5)
				(island_removal_mode 0)
			)
			(polygon
				(pts
					(xy 407.416 -19.6215) (xy 407.924 -19.6215) (xy 407.924 -20.0025) (xy 407.416 -20.0025)
				)
			)
		)
	)
	(footprint ""
		(layer "F.Cu")
		(at 174.244 -8.6995)
		(property "Reference" "R4G9"
			(at 0 0 0)
			(layer "F.SilkS")
			(hide yes)
			(effects
				(font
					(size 1.27 1.27)
				)
			)
		)
		(property "Value" ""
			(at 0 0 0)
			(layer "F.Fab")
			(effects
				(font
					(size 1.27 1.27)
				)
			)
		)
		(duplicate_pad_numbers_are_jumpers no)
		(fp_rect
			(start -0.2794 0.9906)
			(end 0.2794 -0.1016)
			(stroke
				(width 0)
				(type default)
			)
			(fill no)
			(layer "F.CrtYd")
		)
		(fp_line
			(start -0.2794 -0.1016)
			(end -0.2794 0.9906)
			(stroke
				(width 0.1)
				(type default)
			)
			(layer "F.Fab")
		)
		(fp_line
			(start -0.2794 0.9906)
			(end 0.2794 0.9906)
			(stroke
				(width 0.1)
				(type default)
			)
			(layer "F.Fab")
		)
		(fp_line
			(start 0.2794 -0.1016)
			(end -0.2794 -0.1016)
			(stroke
				(width 0.1)
				(type default)
			)
			(layer "F.Fab")
		)
		(fp_line
			(start 0.2794 0.9906)
			(end 0.2794 -0.1016)
			(stroke
				(width 0.1)
				(type default)
			)
			(layer "F.Fab")
		)
		(pad "1" smd rect
			(at 0 0)
			(size 0.508 0.508)
			(layers "F.Cu" "F.Mask" "F.Paste")
			(net "VR_FB_PVPP_GHJ")
		)
		(pad "2" smd rect
			(at 0 0.889)
			(size 0.508 0.508)
			(layers "F.Cu" "F.Mask" "F.Paste")
			(net "AGND_PVPP_GHJ")
		)
		(zone
			(layer "F.Cu")
			(hatch none 0.5)
			(connect_pads
				(clearance 0)
			)
			(min_thickness 0.25)
			(keepout
				(tracks not_allowed)
				(vias allowed)
				(pads allowed)
				(copperpour not_allowed)
				(footprints allowed)
			)
			(placement
				(enabled no)
				(sheetname "")
			)
			(fill
				(thermal_gap 0.5)
				(thermal_bridge_width 0.5)
				(island_removal_mode 0)
			)
			(polygon
				(pts
					(xy 173.99 -8.0645) (xy 174.498 -8.0645) (xy 174.498 -8.4455) (xy 173.99 -8.4455)
				)
			)
		)
		(zone
			(layer "F.Cu")
			(hatch none 0.5)
			(connect_pads
				(clearance 0)
			)
			(min_thickness 0.25)
			(keepout
				(tracks allowed)
				(vias not_allowed)
				(pads allowed)
				(copperpour not_allowed)
				(footprints allowed)
			)
			(placement
				(enabled no)
				(sheetname "")
			)
			(fill
				(thermal_gap 0.5)
				(thermal_bridge_width 0.5)
				(island_removal_mode 0)
			)
			(polygon
				(pts
					(xy 173.99 -8.0645) (xy 174.498 -8.0645) (xy 174.498 -8.4455) (xy 173.99 -8.4455)
				)
			)
		)
	)
	(footprint ""
		(layer "F.Cu")
		(at 317.9826 -29.696918 90)
		(property "Reference" "R6F7"
			(at 0 0 90)
			(layer "F.SilkS")
			(hide yes)
			(effects
				(font
					(size 1.27 1.27)
				)
			)
		)
		(property "Value" ""
			(at 0 0 90)
			(layer "F.Fab")
			(effects
				(font
					(size 1.27 1.27)
				)
			)
		)
		(duplicate_pad_numbers_are_jumpers no)
		(fp_poly
			(pts
				(xy -0.2794 -0.1016) (xy 0.2794 -0.1016) (xy 0.2794 0.9906) (xy -0.2794 0.9906)
			)
			(stroke
				(width 0)
				(type default)
			)
			(fill no)
			(layer "F.CrtYd")
		)
		(fp_line
			(start 0.2794 -0.1016)
			(end -0.2794 -0.1016)
			(stroke
				(width 0.1)
				(type default)
			)
			(layer "F.Fab")
		)
		(fp_line
			(start -0.2794 -0.1016)
			(end -0.2794 0.9906)
			(stroke
				(width 0.1)
				(type default)
			)
			(layer "F.Fab")
		)
		(fp_line
			(start 0.2794 0.9906)
			(end 0.2794 -0.1016)
			(stroke
				(width 0.1)
				(type default)
			)
			(layer "F.Fab")
		)
		(fp_line
			(start -0.2794 0.9906)
			(end 0.2794 0.9906)
			(stroke
				(width 0.1)
				(type default)
			)
			(layer "F.Fab")
		)
		(pad "1" smd rect
			(at 0 0 90)
			(size 0.508 0.508)
			(layers "F.Cu" "F.Mask" "F.Paste")
			(net "CLK_156M_OSC_BRD_CPU0_DN")
		)
		(pad "2" smd rect
			(at 0 0.889 90)
			(size 0.508 0.508)
			(layers "F.Cu" "F.Mask" "F.Paste")
			(net "CLK_156M_OSC_CPU0_HFI_DN")
		)
		(zone
			(layer "F.Cu")
			(hatch none 0.5)
			(connect_pads
				(clearance 0)
			)
			(min_thickness 0.25)
			(keepout
				(tracks allowed)
				(vias not_allowed)
				(pads allowed)
				(copperpour not_allowed)
				(footprints allowed)
			)
			(placement
				(enabled no)
				(sheetname "")
			)
			(fill
				(thermal_gap 0.5)
				(thermal_bridge_width 0.5)
				(island_removal_mode 0)
			)
			(polygon
				(pts
					(xy 318.2366 -29.442918) (xy 318.2366 -29.950918) (xy 318.6176 -29.950918) (xy 318.6176 -29.442918)
				)
			)
		)
		(zone
			(layer "F.Cu")
			(hatch none 0.5)
			(connect_pads
				(clearance 0)
			)
			(min_thickness 0.25)
			(keepout
				(tracks not_allowed)
				(vias allowed)
				(pads allowed)
				(copperpour not_allowed)
				(footprints allowed)
			)
			(placement
				(enabled no)
				(sheetname "")
			)
			(fill
				(thermal_gap 0.5)
				(thermal_bridge_width 0.5)
				(island_removal_mode 0)
			)
			(polygon
				(pts
					(xy 318.6176 -29.442918) (xy 318.6176 -29.950918) (xy 318.2366 -29.950918) (xy 318.2366 -29.442918)
				)
			)
		)
	)
	(footprint ""
		(layer "F.Cu")
		(at 311.34685 -35.615626)
		(property "Reference" "R1W32"
			(at -0.8382 -0.67818 0)
			(unlocked yes)
			(layer "F.SilkS")
			(effects
				(font
					(size 0.4064 0.254)
					(thickness 0.1524)
				)
				(justify left)
			)
		)
		(property "Value" ""
			(at 0 0 0)
			(layer "F.Fab")
			(effects
				(font
					(size 1.27 1.27)
				)
			)
		)
		(duplicate_pad_numbers_are_jumpers no)
		(fp_poly
			(pts
				(xy -0.2794 -0.1016) (xy 0.2794 -0.1016) (xy 0.2794 0.9906) (xy -0.2794 0.9906)
			)
			(stroke
				(width 0)
				(type default)
			)
			(fill no)
			(layer "F.CrtYd")
		)
		(fp_line
			(start -0.2794 -0.1016)
			(end -0.2794 0.9906)
			(stroke
				(width 0.1)
				(type default)
			)
			(layer "F.Fab")
		)
		(fp_line
			(start -0.2794 0.9906)
			(end 0.2794 0.9906)
			(stroke
				(width 0.1)
				(type default)
			)
			(layer "F.Fab")
		)
		(fp_line
			(start 0.2794 -0.1016)
			(end -0.2794 -0.1016)
			(stroke
				(width 0.1)
				(type default)
			)
			(layer "F.Fab")
		)
		(fp_line
			(start 0.2794 0.9906)
			(end 0.2794 -0.1016)
			(stroke
				(width 0.1)
				(type default)
			)
			(layer "F.Fab")
		)
		(pad "1" smd rect
			(at 0 0)
			(size 0.508 0.508)
			(layers "F.Cu" "F.Mask" "F.Paste")
			(net "FM_ADR_COMPLETE_R")
		)
		(pad "2" smd rect
			(at 0 0.889)
			(size 0.508 0.508)
			(layers "F.Cu" "F.Mask" "F.Paste")
			(net "FM_ADR_COMPLETE_CPU0_R")
		)
		(zone
			(layer "F.Cu")
			(hatch none 0.5)
			(connect_pads
				(clearance 0)
			)
			(min_thickness 0.25)
			(keepout
				(tracks allowed)
				(vias not_allowed)
				(pads allowed)
				(copperpour not_allowed)
				(footprints allowed)
			)
			(placement
				(enabled no)
				(sheetname "")
			)
			(fill
				(thermal_gap 0.5)
				(thermal_bridge_width 0.5)
				(island_removal_mode 0)
			)
			(polygon
				(pts
					(xy 311.09285 -35.361626) (xy 311.60085 -35.361626) (xy 311.60085 -34.980626) (xy 311.09285 -34.980626)
				)
			)
		)
		(zone
			(layer "F.Cu")
			(hatch none 0.5)
			(connect_pads
				(clearance 0)
			)
			(min_thickness 0.25)
			(keepout
				(tracks not_allowed)
				(vias allowed)
				(pads allowed)
				(copperpour not_allowed)
				(footprints allowed)
			)
			(placement
				(enabled no)
				(sheetname "")
			)
			(fill
				(thermal_gap 0.5)
				(thermal_bridge_width 0.5)
				(island_removal_mode 0)
			)
			(polygon
				(pts
					(xy 311.09285 -34.980626) (xy 311.60085 -34.980626) (xy 311.60085 -35.361626) (xy 311.09285 -35.361626)
				)
			)
		)
	)
	(footprint ""
		(layer "F.Cu")
		(at 198.178928 -85.733382 90)
		(property "Reference" "C4D47"
			(at 0 0 90)
			(layer "F.SilkS")
			(hide yes)
			(effects
				(font
					(size 1.27 1.27)
				)
			)
		)
		(property "Value" ""
			(at 0 0 90)
			(layer "F.Fab")
			(effects
				(font
					(size 1.27 1.27)
				)
			)
		)
		(duplicate_pad_numbers_are_jumpers no)
		(fp_rect
			(start 0.3048 0.9906)
			(end -0.3048 -0.1016)
			(stroke
				(width 0)
				(type default)
			)
			(fill no)
			(layer "F.CrtYd")
		)
		(fp_line
			(start 0.3048 -0.1016)
			(end -0.3048 -0.1016)
			(stroke
				(width 0.1)
				(type default)
			)
			(layer "F.Fab")
		)
		(fp_line
			(start -0.3048 -0.1016)
			(end -0.3048 0.9906)
			(stroke
				(width 0.1)
				(type default)
			)
			(layer "F.Fab")
		)
		(fp_line
			(start 0.3048 0.9906)
			(end 0.3048 -0.1016)
			(stroke
				(width 0.1)
				(type default)
			)
			(layer "F.Fab")
		)
		(fp_line
			(start -0.3048 0.9906)
			(end 0.3048 0.9906)
			(stroke
				(width 0.1)
				(type default)
			)
			(layer "F.Fab")
		)
		(pad "1" smd rect
			(at 0 0 90)
			(size 0.508 0.508)
			(layers "F.Cu" "F.Mask" "F.Paste")
			(net "P5V_STBY")
		)
		(pad "2" smd rect
			(at 0 0.889 90)
			(size 0.508 0.508)
			(layers "F.Cu" "F.Mask" "F.Paste")
			(net "GND")
		)
		(zone
			(layer "F.Cu")
			(hatch none 0.5)
			(connect_pads
				(clearance 0)
			)
			(min_thickness 0.25)
			(keepout
				(tracks allowed)
				(vias not_allowed)
				(pads allowed)
				(copperpour not_allowed)
				(footprints allowed)
			)
			(placement
				(enabled no)
				(sheetname "")
			)
			(fill
				(thermal_gap 0.5)
				(thermal_bridge_width 0.5)
				(island_removal_mode 0)
			)
			(polygon
				(pts
					(xy 198.813928 -85.987382) (xy 198.432928 -85.987382) (xy 198.432928 -85.479382) (xy 198.813928 -85.479382)
				)
			)
		)
		(zone
			(layer "F.Cu")
			(hatch none 0.5)
			(connect_pads
				(clearance 0)
			)
			(min_thickness 0.25)
			(keepout
				(tracks not_allowed)
				(vias allowed)
				(pads allowed)
				(copperpour not_allowed)
				(footprints allowed)
			)
			(placement
				(enabled no)
				(sheetname "")
			)
			(fill
				(thermal_gap 0.5)
				(thermal_bridge_width 0.5)
				(island_removal_mode 0)
			)
			(polygon
				(pts
					(xy 198.813928 -85.987382) (xy 198.432928 -85.987382) (xy 198.432928 -85.479382) (xy 198.813928 -85.479382)
				)
			)
		)
	)
	(footprint ""
		(layer "F.Cu")
		(at 393.103354 -86.295484)
		(property "Reference" "R7D19"
			(at 0 0 0)
			(layer "F.SilkS")
			(hide yes)
			(effects
				(font
					(size 1.27 1.27)
				)
			)
		)
		(property "Value" ""
			(at 0 0 0)
			(layer "F.Fab")
			(effects
				(font
					(size 1.27 1.27)
				)
			)
		)
		(duplicate_pad_numbers_are_jumpers no)
		(fp_poly
			(pts
				(xy -0.2794 -0.1016) (xy 0.2794 -0.1016) (xy 0.2794 0.9906) (xy -0.2794 0.9906)
			)
			(stroke
				(width 0)
				(type default)
			)
			(fill no)
			(layer "F.CrtYd")
		)
		(fp_line
			(start -0.2794 -0.1016)
			(end -0.2794 0.9906)
			(stroke
				(width 0.1)
				(type default)
			)
			(layer "F.Fab")
		)
		(fp_line
			(start -0.2794 0.9906)
			(end 0.2794 0.9906)
			(stroke
				(width 0.1)
				(type default)
			)
			(layer "F.Fab")
		)
		(fp_line
			(start 0.2794 -0.1016)
			(end -0.2794 -0.1016)
			(stroke
				(width 0.1)
				(type default)
			)
			(layer "F.Fab")
		)
		(fp_line
			(start 0.2794 0.9906)
			(end 0.2794 -0.1016)
			(stroke
				(width 0.1)
				(type default)
			)
			(layer "F.Fab")
		)
		(pad "1" smd rect
			(at 0 0)
			(size 0.508 0.508)
			(layers "F.Cu" "F.Mask" "F.Paste")
			(net "FM_OC_DETECT_EN_N")
		)
		(pad "2" smd rect
			(at 0 0.889)
			(size 0.508 0.508)
			(layers "F.Cu" "F.Mask" "F.Paste")
			(net "GND")
		)
		(zone
			(layer "F.Cu")
			(hatch none 0.5)
			(connect_pads
				(clearance 0)
			)
			(min_thickness 0.25)
			(keepout
				(tracks allowed)
				(vias not_allowed)
				(pads allowed)
				(copperpour not_allowed)
				(footprints allowed)
			)
			(placement
				(enabled no)
				(sheetname "")
			)
			(fill
				(thermal_gap 0.5)
				(thermal_bridge_width 0.5)
				(island_removal_mode 0)
			)
			(polygon
				(pts
					(xy 392.849354 -86.041484) (xy 393.357354 -86.041484) (xy 393.357354 -85.660484) (xy 392.849354 -85.660484)
				)
			)
		)
		(zone
			(layer "F.Cu")
			(hatch none 0.5)
			(connect_pads
				(clearance 0)
			)
			(min_thickness 0.25)
			(keepout
				(tracks not_allowed)
				(vias allowed)
				(pads allowed)
				(copperpour not_allowed)
				(footprints allowed)
			)
			(placement
				(enabled no)
				(sheetname "")
			)
			(fill
				(thermal_gap 0.5)
				(thermal_bridge_width 0.5)
				(island_removal_mode 0)
			)
			(polygon
				(pts
					(xy 392.849354 -85.660484) (xy 393.357354 -85.660484) (xy 393.357354 -86.041484) (xy 392.849354 -86.041484)
				)
			)
		)
	)
)
